# S9S_MB_2U (Grand Teton) — schematic netlist excerpt (pin names and nets, part order shuffled) for the footprints in the layout excerpt that follows; sources: Cadence DE-HDL packaged netlist, KiCad conversion of 03242023_DA0F0TMBIJ0_F0T_Motherboard_J_brd_V01_OCP.brd

C2039  Q_CAP  0.1UF 25V 10% X7R  pkg 0402  page 152 : A = P3V3_AUX_USB_HUB ; B = GND
C112  Q_CAP  0.047UF 25V 10% X7R  pkg C0402  page 210 : A = P3V3_AUX_CLK_GEN_VDDXTAL_CK440 ; B = GND

(kicad_pcb
	(version 20260206)
	(generator "pcbnew")
	(generator_version "10.0")
	(general
		(thickness 1.6)
		(legacy_teardrops no)
	)
	(paper "A4")
	(title_block
		(title "03242023_DA0F0TMBIJ0_F0T_Motherboard_J_brd_V01_OCP.brd")
		(comment 1 "Grand Teton / footprints 4864-4865 of 6105")
	)
	(layers
		(0 "F.Cu" signal "TOP")
		(4 "In1.Cu" signal "GND")
		(6 "In2.Cu" signal "IN1")
		(8 "In3.Cu" signal "GND1")
		(10 "In4.Cu" signal "IN2")
		(12 "In5.Cu" signal "GND2")
		(14 "In6.Cu" signal "IN3")
		(16 "In7.Cu" signal "GND3")
		(18 "In8.Cu" signal "VCC")
		(20 "In9.Cu" signal "VCC1")
		(22 "In10.Cu" signal "GND4")
		(24 "In11.Cu" signal "IN4")
		(26 "In12.Cu" signal "GND5")
		(28 "In13.Cu" signal "IN5")
		(30 "In14.Cu" signal "GND6")
		(32 "In15.Cu" signal "IN6")
		(34 "In16.Cu" signal "GND7")
		(2 "B.Cu" signal "BOTTOM")
		(9 "F.Adhes" user "F.Adhesive")
		(11 "B.Adhes" user "B.Adhesive")
		(13 "F.Paste" user "Package Geometry/Pastemask Top")
		(15 "B.Paste" user "Package Geometry/Pastemask Bottom")
		(5 "F.SilkS" user "Ref Des/Silkscreen Top")
		(7 "B.SilkS" user "Ref Des/Silkscreen Bottom")
		(1 "F.Mask" user "Board Geometry/Soldermask Top")
		(3 "B.Mask" user "Board Geometry/Soldermask Bottom")
		(17 "Dwgs.User" user "User.Drawings")
		(19 "Cmts.User" user "User.Comments")
		(21 "Eco1.User" user "User.Eco1")
		(23 "Eco2.User" user "User.Eco2")
		(25 "Edge.Cuts" user "Board Geometry/Outline")
		(27 "Margin" user)
		(31 "F.CrtYd" user "Package Geometry/Place Bound Top")
		(29 "B.CrtYd" user "Package Geometry/Place Bound Bottom")
		(35 "F.Fab" user "Ref Des/Assembly Top")
		(33 "B.Fab" user "Ref Des/Assembly Bottom")
	)
	(footprint ""
		(layer "B.Cu")
		(at 16.610838 -97.314512 90)
		(property "Reference" "C2039"
			(at 0 0 90)
			(layer "B.SilkS")
			(hide yes)
			(effects
				(font
					(size 1.27 1.27)
				)
				(justify mirror)
			)
		)
		(property "Value" ""
			(at 0 0 90)
			(layer "B.Fab")
			(effects
				(font
					(size 1.27 1.27)
				)
				(justify mirror)
			)
		)
		(duplicate_pad_numbers_are_jumpers no)
		(fp_line
			(start 0.7874 -0.4064)
			(end -0.7874 -0.4064)
			(stroke
				(width 0.1524)
				(type default)
			)
			(layer "B.SilkS")
		)
		(fp_line
			(start -0.7874 -0.4064)
			(end -0.7874 0.4064)
			(stroke
				(width 0.1524)
				(type default)
			)
			(layer "B.SilkS")
		)
		(fp_line
			(start 0.7874 0.4064)
			(end 0.7874 -0.4064)
			(stroke
				(width 0.1524)
				(type default)
			)
			(layer "B.SilkS")
		)
		(fp_line
			(start -0.7874 0.4064)
			(end 0.7874 0.4064)
			(stroke
				(width 0.1524)
				(type default)
			)
			(layer "B.SilkS")
		)
		(fp_line
			(start 0.67945 -0.305054)
			(end 0.12065 -0.305054)
			(stroke
				(width 0.1)
				(type default)
			)
			(layer "B.Fab")
		)
		(fp_line
			(start 0.12065 -0.305054)
			(end 0.12065 -0.2794)
			(stroke
				(width 0.1)
				(type default)
			)
			(layer "B.Fab")
		)
		(fp_line
			(start -0.12065 -0.3048)
			(end -0.67945 -0.3048)
			(stroke
				(width 0.1)
				(type default)
			)
			(layer "B.Fab")
		)
		(fp_line
			(start -0.67945 -0.3048)
			(end -0.67945 0.3048)
			(stroke
				(width 0.1)
				(type default)
			)
			(layer "B.Fab")
		)
		(fp_line
			(start 0.12065 -0.2794)
			(end -0.12065 -0.2794)
			(stroke
				(width 0.1)
				(type default)
			)
			(layer "B.Fab")
		)
		(fp_line
			(start -0.12065 -0.2794)
			(end -0.12065 -0.3048)
			(stroke
				(width 0.1)
				(type default)
			)
			(layer "B.Fab")
		)
		(fp_line
			(start 0.12065 0.2794)
			(end 0.12065 0.3048)
			(stroke
				(width 0.1)
				(type default)
			)
			(layer "B.Fab")
		)
		(fp_line
			(start -0.120396 0.2794)
			(end 0.12065 0.2794)
			(stroke
				(width 0.1)
				(type default)
			)
			(layer "B.Fab")
		)
		(fp_line
			(start 0.67945 0.3048)
			(end 0.67945 -0.305054)
			(stroke
				(width 0.1)
				(type default)
			)
			(layer "B.Fab")
		)
		(fp_line
			(start 0.12065 0.3048)
			(end 0.67945 0.3048)
			(stroke
				(width 0.1)
				(type default)
			)
			(layer "B.Fab")
		)
		(fp_line
			(start -0.120396 0.3048)
			(end -0.120396 0.2794)
			(stroke
				(width 0.1)
				(type default)
			)
			(layer "B.Fab")
		)
		(fp_line
			(start -0.67945 0.3048)
			(end -0.120396 0.3048)
			(stroke
				(width 0.1)
				(type default)
			)
			(layer "B.Fab")
		)
		(pad "1" smd circle
			(at 0.40005 0 270)
			(size 0 0)
			(layers "B.Cu" "B.Mask" "B.Paste")
			(net "P3V3_AUX_USB_HUB")
		)
		(pad "2" smd circle
			(at -0.40005 0 270)
			(size 0 0)
			(layers "B.Cu" "B.Mask" "B.Paste")
			(net "GND")
		)
	)
	(footprint ""
		(layer "B.Cu")
		(at 244.20703 -97.219516 -90)
		(property "Reference" "C112"
			(at 0 0 90)
			(layer "B.SilkS")
			(hide yes)
			(effects
				(font
					(size 1.27 1.27)
				)
				(justify mirror)
			)
		)
		(property "Value" ""
			(at 0 0 90)
			(layer "B.Fab")
			(effects
				(font
					(size 1.27 1.27)
				)
				(justify mirror)
			)
		)
		(duplicate_pad_numbers_are_jumpers no)
		(fp_line
			(start -0.7874 0.4064)
			(end 0.7874 0.4064)
			(stroke
				(width 0.1524)
				(type default)
			)
			(layer "B.SilkS")
		)
		(fp_line
			(start 0.7874 0.4064)
			(end 0.7874 -0.4064)
			(stroke
				(width 0.1524)
				(type default)
			)
			(layer "B.SilkS")
		)
		(fp_line
			(start -0.7874 -0.4064)
			(end -0.7874 0.4064)
			(stroke
				(width 0.1524)
				(type default)
			)
			(layer "B.SilkS")
		)
		(fp_line
			(start 0.7874 -0.4064)
			(end -0.7874 -0.4064)
			(stroke
				(width 0.1524)
				(type default)
			)
			(layer "B.SilkS")
		)
		(fp_line
			(start -0.67945 0.3048)
			(end -0.120396 0.3048)
			(stroke
				(width 0.1)
				(type default)
			)
			(layer "B.Fab")
		)
		(fp_line
			(start -0.120396 0.3048)
			(end -0.120396 0.2794)
			(stroke
				(width 0.1)
				(type default)
			)
			(layer "B.Fab")
		)
		(fp_line
			(start 0.12065 0.3048)
			(end 0.67945 0.3048)
			(stroke
				(width 0.1)
				(type default)
			)
			(layer "B.Fab")
		)
		(fp_line
			(start 0.67945 0.3048)
			(end 0.67945 -0.305054)
			(stroke
				(width 0.1)
				(type default)
			)
			(layer "B.Fab")
		)
		(fp_line
			(start -0.120396 0.2794)
			(end 0.12065 0.2794)
			(stroke
				(width 0.1)
				(type default)
			)
			(layer "B.Fab")
		)
		(fp_line
			(start 0.12065 0.2794)
			(end 0.12065 0.3048)
			(stroke
				(width 0.1)
				(type default)
			)
			(layer "B.Fab")
		)
		(fp_line
			(start -0.12065 -0.2794)
			(end -0.12065 -0.3048)
			(stroke
				(width 0.1)
				(type default)
			)
			(layer "B.Fab")
		)
		(fp_line
			(start 0.12065 -0.2794)
			(end -0.12065 -0.2794)
			(stroke
				(width 0.1)
				(type default)
			)
			(layer "B.Fab")
		)
		(fp_line
			(start -0.67945 -0.3048)
			(end -0.67945 0.3048)
			(stroke
				(width 0.1)
				(type default)
			)
			(layer "B.Fab")
		)
		(fp_line
			(start -0.12065 -0.3048)
			(end -0.67945 -0.3048)
			(stroke
				(width 0.1)
				(type default)
			)
			(layer "B.Fab")
		)
		(fp_line
			(start 0.12065 -0.305054)
			(end 0.12065 -0.2794)
			(stroke
				(width 0.1)
				(type default)
			)
			(layer "B.Fab")
		)
		(fp_line
			(start 0.67945 -0.305054)
			(end 0.12065 -0.305054)
			(stroke
				(width 0.1)
				(type default)
			)
			(layer "B.Fab")
		)
		(pad "1" smd circle
			(at 0.40005 0 90)
			(size 0 0)
			(layers "B.Cu" "B.Mask" "B.Paste")
			(net "P3V3_AUX_CLK_GEN_VDDXTAL_CK440")
		)
		(pad "2" smd circle
			(at -0.40005 0 90)
			(size 0 0)
			(layers "B.Cu" "B.Mask" "B.Paste")
			(net "GND")
		)
	)
)
